(kicad_pcb
	(version 20241229)
	(generator "pcbnew")
	(generator_version "9.0")
	(general
		(thickness 1.6642)
		(legacy_teardrops no)
	)
	(paper "A3")
	(title_block
		(title "PolarFire SoM")
		(date "2025-07-22")
		(rev "1.1.4")
		(company "Antmicro Ltd")
		(comment 1 "www.antmicro.com")
		(comment 9 "footprints 259-262 of 470")
	)
	(layers
		(0 "F.Cu" mixed)
		(4 "In1.Cu" power)
		(6 "In2.Cu" signal)
		(8 "In3.Cu" power)
		(10 "In4.Cu" signal)
		(12 "In5.Cu" power)
		(14 "In6.Cu" power)
		(16 "In7.Cu" signal)
		(18 "In8.Cu" power)
		(20 "In9.Cu" signal)
		(22 "In10.Cu" power)
		(24 "In11.Cu" signal)
		(26 "In12.Cu" signal)
		(2 "B.Cu" mixed)
		(9 "F.Adhes" user "F.Adhesive")
		(11 "B.Adhes" user "B.Adhesive")
		(13 "F.Paste" user)
		(15 "B.Paste" user)
		(5 "F.SilkS" user "F.Silkscreen")
		(7 "B.SilkS" user "B.Silkscreen")
		(1 "F.Mask" user)
		(3 "B.Mask" user)
		(17 "Dwgs.User" user "User.Drawings")
		(19 "Cmts.User" user "User.Comments")
		(21 "Eco1.User" user "User.Eco1")
		(23 "Eco2.User" user "User.Eco2")
		(25 "Edge.Cuts" user)
		(27 "Margin" user)
		(31 "F.CrtYd" user "F.Courtyard")
		(29 "B.CrtYd" user "B.Courtyard")
		(35 "F.Fab" user)
		(33 "B.Fab" user)
	)
	(footprint "antmicro-footprints:C_0402_1005Metric"
		(layer "B.Cu")
		(at 208.1 150.33 180)
		(descr "Capacitor SMD 0402")
		(tags "capacitor SMD 0402")
		(property "Reference" "C248"
			(at 4.9 18.375 0)
			(layer "B.SilkS")
			(effects
				(font
					(size 0.7 0.7)
					(thickness 0.15)
				)
				(justify left bottom mirror)
			)
		)
		(property "Value" "C_10u_10V_0402"
			(at -1.022927 -2.155213 0)
			(layer "B.Fab")
			(hide yes)
			(effects
				(font
					(size 0.7 0.7)
					(thickness 0.15)
				)
				(justify left bottom mirror)
			)
		)
		(property "Datasheet" "https://www.murata.com/products/productdetail?partno=GRM155R61A106ME11%23"
			(at 0 0 180)
			(layer "F.Fab")
			(hide yes)
			(effects
				(font
					(size 1.27 1.27)
					(thickness 0.15)
				)
			)
		)
		(property "Description" "Multilayer Ceramic Capacitors MLCC - SMD/SMT 10 uF 10 VDC 20% 0402 X5R"
			(at 0 0 180)
			(layer "F.Fab")
			(hide yes)
			(effects
				(font
					(size 1.27 1.27)
					(thickness 0.15)
				)
			)
		)
		(property "Author" "Antmicro"
			(at 416.2 300.66 0)
			(layer "B.Fab")
			(hide yes)
			(effects
				(font
					(size 1 1)
					(thickness 0.15)
				)
				(justify mirror)
			)
		)
		(property "Dielectric" "X5R"
			(at 416.2 300.66 0)
			(layer "B.Fab")
			(hide yes)
			(effects
				(font
					(size 1 1)
					(thickness 0.15)
				)
				(justify mirror)
			)
		)
		(property "License" "Apache-2.0"
			(at 416.2 300.66 0)
			(layer "B.Fab")
			(hide yes)
			(effects
				(font
					(size 1 1)
					(thickness 0.15)
				)
				(justify mirror)
			)
		)
		(property "MPN" "GRM155R61A106ME11D"
			(at 416.2 300.66 0)
			(layer "B.Fab")
			(hide yes)
			(effects
				(font
					(size 1 1)
					(thickness 0.15)
				)
				(justify mirror)
			)
		)
		(property "Manufacturer" "Murata"
			(at 416.2 300.66 0)
			(layer "B.Fab")
			(hide yes)
			(effects
				(font
					(size 1 1)
					(thickness 0.15)
				)
				(justify mirror)
			)
		)
		(property "Public" ""
			(at 416.2 300.66 0)
			(layer "B.Fab")
			(hide yes)
			(effects
				(font
					(size 1 1)
					(thickness 0.15)
				)
				(justify mirror)
			)
		)
		(property "Val" "10u"
			(at 416.2 300.66 0)
			(layer "B.Fab")
			(hide yes)
			(effects
				(font
					(size 1 1)
					(thickness 0.15)
				)
				(justify mirror)
			)
		)
		(property "Voltage" "10V"
			(at 416.2 300.66 0)
			(layer "B.Fab")
			(hide yes)
			(effects
				(font
					(size 1 1)
					(thickness 0.15)
				)
				(justify mirror)
			)
		)
		(sheetname "/MIPI CrossLink/")
		(sheetfile "crosslink.kicad_sch")
		(attr smd)
		(fp_rect
			(start -0.925 0.47)
			(end 0.925 -0.47)
			(stroke
				(width 0.05)
				(type default)
			)
			(fill no)
			(layer "B.CrtYd")
		)
		(fp_line
			(start 0.504 0.25)
			(end 0.504 -0.248)
			(stroke
				(width 0.15)
				(type solid)
			)
			(layer "B.Fab")
		)
		(fp_line
			(start 0.504 -0.248)
			(end -0.494 -0.248)
			(stroke
				(width 0.15)
				(type solid)
			)
			(layer "B.Fab")
		)
		(fp_line
			(start -0.494 0.25)
			(end 0.504 0.25)
			(stroke
				(width 0.15)
				(type solid)
			)
			(layer "B.Fab")
		)
		(fp_line
			(start -0.494 -0.248)
			(end -0.494 0.25)
			(stroke
				(width 0.15)
				(type solid)
			)
			(layer "B.Fab")
		)
		(fp_text user "${REFERENCE}"
			(at -0.939 -4.599 0)
			(layer "B.Fab")
			(effects
				(font
					(size 0.7 0.7)
					(thickness 0.15)
				)
				(justify left bottom mirror)
			)
		)
		(fp_text user "Author: Antmicro"
			(at -0.939 -3.399 0)
			(layer "B.Fab")
			(effects
				(font
					(size 0.7 0.7)
					(thickness 0.15)
				)
				(justify left bottom mirror)
			)
		)
		(fp_text user "License: Apache-2.0"
			(at -0.939 -5.799 0)
			(layer "B.Fab")
			(effects
				(font
					(size 0.7 0.7)
					(thickness 0.15)
				)
				(justify left bottom mirror)
			)
		)
		(pad "1" smd roundrect
			(at -0.48 0 180)
			(size 0.59 0.64)
			(layers "B.Cu" "B.Mask" "B.Paste")
			(roundrect_rratio 0.25)
			(net 417 "GND")
			(pintype "passive")
		)
		(pad "2" smd roundrect
			(at 0.48 0 180)
			(size 0.59 0.64)
			(layers "B.Cu" "B.Mask" "B.Paste")
			(roundrect_rratio 0.25)
			(net 204 "/MIPI CrossLink/CL_VCCPLL_DPHY0")
			(pintype "passive")
		)
	)
	(footprint "antmicro-footprints:C_0402_1005Metric"
		(layer "B.Cu")
		(at 195.3 125.77)
		(descr "Capacitor SMD 0402")
		(tags "capacitor SMD 0402")
		(property "Reference" "C17"
			(at -3 -0.095 0)
			(layer "B.SilkS")
			(effects
				(font
					(size 0.7 0.7)
					(thickness 0.15)
				)
				(justify right bottom mirror)
			)
		)
		(property "Value" "C_100n_0402"
			(at -1.022927 -2.155213 0)
			(layer "B.Fab")
			(hide yes)
			(effects
				(font
					(size 0.7 0.7)
					(thickness 0.15)
				)
				(justify right bottom mirror)
			)
		)
		(property "Datasheet" "https://www.murata.com/products/productdetail?partno=GRM155R61H104KE14%23"
			(at 0 0 0)
			(layer "F.Fab")
			(hide yes)
			(effects
				(font
					(size 1.27 1.27)
					(thickness 0.15)
				)
			)
		)
		(property "Description" "SMD Multilayer Ceramic Capacitor, 0.1 µF, 50 V, 0402 [1005 Metric], ± 10%, X5R, GRM Series"
			(at 0 0 0)
			(layer "F.Fab")
			(hide yes)
			(effects
				(font
					(size 1.27 1.27)
					(thickness 0.15)
				)
			)
		)
		(property "Author" "Antmicro"
			(at 0 0 0)
			(layer "B.Fab")
			(hide yes)
			(effects
				(font
					(size 1 1)
					(thickness 0.15)
				)
				(justify mirror)
			)
		)
		(property "Dielectric" "X5R"
			(at 0 0 0)
			(layer "B.Fab")
			(hide yes)
			(effects
				(font
					(size 1 1)
					(thickness 0.15)
				)
				(justify mirror)
			)
		)
		(property "License" "Apache-2.0"
			(at 0 0 0)
			(layer "B.Fab")
			(hide yes)
			(effects
				(font
					(size 1 1)
					(thickness 0.15)
				)
				(justify mirror)
			)
		)
		(property "MPN" "GRM155R61H104KE14D"
			(at 0 0 0)
			(layer "B.Fab")
			(hide yes)
			(effects
				(font
					(size 1 1)
					(thickness 0.15)
				)
				(justify mirror)
			)
		)
		(property "Manufacturer" "Murata"
			(at 0 0 0)
			(layer "B.Fab")
			(hide yes)
			(effects
				(font
					(size 1 1)
					(thickness 0.15)
				)
				(justify mirror)
			)
		)
		(property "Public" ""
			(at 0 0 0)
			(layer "B.Fab")
			(hide yes)
			(effects
				(font
					(size 1 1)
					(thickness 0.15)
				)
				(justify mirror)
			)
		)
		(property "Val" "100n"
			(at 0 0 0)
			(layer "B.Fab")
			(hide yes)
			(effects
				(font
					(size 1 1)
					(thickness 0.15)
				)
				(justify mirror)
			)
		)
		(property "Voltage" "50V"
			(at 0 0 0)
			(layer "B.Fab")
			(hide yes)
			(effects
				(font
					(size 1 1)
					(thickness 0.15)
				)
				(justify mirror)
			)
		)
		(sheetname "/FPGA Supply/")
		(sheetfile "fpga-supply.kicad_sch")
		(attr smd)
		(fp_rect
			(start -0.925 0.47)
			(end 0.925 -0.47)
			(stroke
				(width 0.05)
				(type default)
			)
			(fill no)
			(layer "B.CrtYd")
		)
		(fp_line
			(start -0.494 -0.248)
			(end -0.494 0.25)
			(stroke
				(width 0.15)
				(type solid)
			)
			(layer "B.Fab")
		)
		(fp_line
			(start -0.494 0.25)
			(end 0.504 0.25)
			(stroke
				(width 0.15)
				(type solid)
			)
			(layer "B.Fab")
		)
		(fp_line
			(start 0.504 -0.248)
			(end -0.494 -0.248)
			(stroke
				(width 0.15)
				(type solid)
			)
			(layer "B.Fab")
		)
		(fp_line
			(start 0.504 0.25)
			(end 0.504 -0.248)
			(stroke
				(width 0.15)
				(type solid)
			)
			(layer "B.Fab")
		)
		(fp_text user "Author: Antmicro"
			(at -0.939 -3.399 180)
			(layer "B.Fab")
			(effects
				(font
					(size 0.7 0.7)
					(thickness 0.15)
				)
				(justify left bottom mirror)
			)
		)
		(fp_text user "${REFERENCE}"
			(at -0.939 -4.599 180)
			(layer "B.Fab")
			(effects
				(font
					(size 0.7 0.7)
					(thickness 0.15)
				)
				(justify left bottom mirror)
			)
		)
		(fp_text user "License: Apache-2.0"
			(at -0.939 -5.799 180)
			(layer "B.Fab")
			(effects
				(font
					(size 0.7 0.7)
					(thickness 0.15)
				)
				(justify left bottom mirror)
			)
		)
		(pad "1" smd roundrect
			(at -0.48 0)
			(size 0.59 0.64)
			(layers "B.Cu" "B.Mask" "B.Paste")
			(roundrect_rratio 0.25)
			(net 417 "GND")
			(pintype "passive")
		)
		(pad "2" smd roundrect
			(at 0.48 0)
			(size 0.59 0.64)
			(layers "B.Cu" "B.Mask" "B.Paste")
			(roundrect_rratio 0.25)
			(net 2 "+1V1")
			(pintype "passive")
		)
	)
	(footprint "antmicro-footprints:C_0402_1005Metric"
		(layer "B.Cu")
		(at 180 123.1 90)
		(descr "Capacitor SMD 0402")
		(tags "capacitor SMD 0402")
		(property "Reference" "C264"
			(at 0.75 0.21 225)
			(layer "B.SilkS")
			(effects
				(font
					(size 0.7 0.7)
					(thickness 0.15)
				)
				(justify right bottom mirror)
			)
		)
		(property "Value" "C_10u_0402"
			(at -1.022927 -2.155213 90)
			(layer "B.Fab")
			(hide yes)
			(effects
				(font
					(size 0.7 0.7)
					(thickness 0.15)
				)
				(justify right bottom mirror)
			)
		)
		(property "Datasheet" "https://www.yageo.com/en/Chart/Download/pdf/CC0402MRX5R5BB106"
			(at 0 0 90)
			(layer "F.Fab")
			(hide yes)
			(effects
				(font
					(size 1.27 1.27)
					(thickness 0.15)
				)
			)
		)
		(property "Description" "SMD Multilayer Ceramic Capacitor, 10 µF, 6.3 V, 0402 [1005 Metric], ± 20%, X5R, CC Series"
			(at 0 0 90)
			(layer "F.Fab")
			(hide yes)
			(effects
				(font
					(size 1.27 1.27)
					(thickness 0.15)
				)
			)
		)
		(property "Author" "Antmicro"
			(at 303.1 -56.9 0)
			(layer "B.Fab")
			(hide yes)
			(effects
				(font
					(size 1 1)
					(thickness 0.15)
				)
				(justify mirror)
			)
		)
		(property "Dielectric" ""
			(at 303.1 -56.9 0)
			(layer "B.Fab")
			(hide yes)
			(effects
				(font
					(size 1 1)
					(thickness 0.15)
				)
				(justify mirror)
			)
		)
		(property "License" "Apache-2.0"
			(at 303.1 -56.9 0)
			(layer "B.Fab")
			(hide yes)
			(effects
				(font
					(size 1 1)
					(thickness 0.15)
				)
				(justify mirror)
			)
		)
		(property "MPN" "CC0402MRX5R5BB106"
			(at 303.1 -56.9 0)
			(layer "B.Fab")
			(hide yes)
			(effects
				(font
					(size 1 1)
					(thickness 0.15)
				)
				(justify mirror)
			)
		)
		(property "Manufacturer" "YAGEO"
			(at 303.1 -56.9 0)
			(layer "B.Fab")
			(hide yes)
			(effects
				(font
					(size 1 1)
					(thickness 0.15)
				)
				(justify mirror)
			)
		)
		(property "Public" ""
			(at 303.1 -56.9 0)
			(layer "B.Fab")
			(hide yes)
			(effects
				(font
					(size 1 1)
					(thickness 0.15)
				)
				(justify mirror)
			)
		)
		(property "Val" "10u"
			(at 303.1 -56.9 0)
			(layer "B.Fab")
			(hide yes)
			(effects
				(font
					(size 1 1)
					(thickness 0.15)
				)
				(justify mirror)
			)
		)
		(property "Voltage" ""
			(at 303.1 -56.9 0)
			(layer "B.Fab")
			(hide yes)
			(effects
				(font
					(size 1 1)
					(thickness 0.15)
				)
				(justify mirror)
			)
		)
		(sheetname "/LPDDR4/")
		(sheetfile "lpddr.kicad_sch")
		(attr smd)
		(fp_rect
			(start -0.925 0.47)
			(end 0.925 -0.47)
			(stroke
				(width 0.05)
				(type default)
			)
			(fill no)
			(layer "B.CrtYd")
		)
		(fp_line
			(start 0.504 -0.248)
			(end -0.494 -0.248)
			(stroke
				(width 0.15)
				(type solid)
			)
			(layer "B.Fab")
		)
		(fp_line
			(start -0.494 -0.248)
			(end -0.494 0.25)
			(stroke
				(width 0.15)
				(type solid)
			)
			(layer "B.Fab")
		)
		(fp_line
			(start 0.504 0.25)
			(end 0.504 -0.248)
			(stroke
				(width 0.15)
				(type solid)
			)
			(layer "B.Fab")
		)
		(fp_line
			(start -0.494 0.25)
			(end 0.504 0.25)
			(stroke
				(width 0.15)
				(type solid)
			)
			(layer "B.Fab")
		)
		(fp_text user "Author: Antmicro"
			(at -0.939 -3.399 270)
			(layer "B.Fab")
			(effects
				(font
					(size 0.7 0.7)
					(thickness 0.15)
				)
				(justify left bottom mirror)
			)
		)
		(fp_text user "License: Apache-2.0"
			(at -0.939 -5.799 270)
			(layer "B.Fab")
			(effects
				(font
					(size 0.7 0.7)
					(thickness 0.15)
				)
				(justify left bottom mirror)
			)
		)
		(fp_text user "${REFERENCE}"
			(at -0.939 -4.599 270)
			(layer "B.Fab")
			(effects
				(font
					(size 0.7 0.7)
					(thickness 0.15)
				)
				(justify left bottom mirror)
			)
		)
		(pad "1" smd roundrect
			(at -0.48 0 90)
			(size 0.59 0.64)
			(layers "B.Cu" "B.Mask" "B.Paste")
			(roundrect_rratio 0.25)
			(net 417 "GND")
			(pintype "passive")
		)
		(pad "2" smd roundrect
			(at 0.48 0 90)
			(size 0.59 0.64)
			(layers "B.Cu" "B.Mask" "B.Paste")
			(roundrect_rratio 0.25)
			(net 2 "+1V1")
			(pintype "passive")
		)
	)
	(footprint "antmicro-footprints:R_0402_1005Metric"
		(layer "B.Cu")
		(at 218.975 135.775 180)
		(descr "Resistor SMD 0402")
		(tags "resistor SMD 0402")
		(property "Reference" "R8"
			(at 0.75 -0.475 0)
			(layer "B.SilkS")
			(effects
				(font
					(size 0.7 0.7)
					(thickness 0.15)
				)
				(justify left bottom mirror)
			)
		)
		(property "Value" "R_0R_0402"
			(at -1.011843 -1.772047 0)
			(layer "B.Fab")
			(hide yes)
			(effects
				(font
					(size 0.7 0.7)
					(thickness 0.15)
				)
				(justify left bottom mirror)
			)
		)
		(property "Datasheet" "https://industrial.panasonic.com/cdbs/www-data/pdf/RDA0000/AOA0000C301.pdf"
			(at 0 0 180)
			(layer "F.Fab")
			(hide yes)
			(effects
				(font
					(size 1.27 1.27)
					(thickness 0.15)
				)
			)
		)
		(property "Description" "SMD Chip Resistor, Jumper, 0 ohm, 100 mW, 0402 [1005 Metric], Thick Film, General Purpose"
			(at 0 0 180)
			(layer "F.Fab")
			(hide yes)
			(effects
				(font
					(size 1.27 1.27)
					(thickness 0.15)
				)
			)
		)
		(property "Author" "Antmicro"
			(at 437.95 271.55 0)
			(layer "B.Fab")
			(hide yes)
			(effects
				(font
					(size 1 1)
					(thickness 0.15)
				)
				(justify mirror)
			)
		)
		(property "Current" "1A"
			(at 437.95 271.55 0)
			(layer "B.Fab")
			(hide yes)
			(effects
				(font
					(size 1 1)
					(thickness 0.15)
				)
				(justify mirror)
			)
		)
		(property "License" "Apache-2.0"
			(at 437.95 271.55 0)
			(layer "B.Fab")
			(hide yes)
			(effects
				(font
					(size 1 1)
					(thickness 0.15)
				)
				(justify mirror)
			)
		)
		(property "MPN" "ERJ2GE0R00X"
			(at 437.95 271.55 0)
			(layer "B.Fab")
			(hide yes)
			(effects
				(font
					(size 1 1)
					(thickness 0.15)
				)
				(justify mirror)
			)
		)
		(property "Manufacturer" "Panasonic"
			(at 437.95 271.55 0)
			(layer "B.Fab")
			(hide yes)
			(effects
				(font
					(size 1 1)
					(thickness 0.15)
				)
				(justify mirror)
			)
		)
		(property "Public" ""
			(at 437.95 271.55 0)
			(layer "B.Fab")
			(hide yes)
			(effects
				(font
					(size 1 1)
					(thickness 0.15)
				)
				(justify mirror)
			)
		)
		(property "Tolerance" "~"
			(at 437.95 271.55 0)
			(layer "B.Fab")
			(hide yes)
			(effects
				(font
					(size 1 1)
					(thickness 0.15)
				)
				(justify mirror)
			)
		)
		(property "Val" "0R"
			(at 437.95 271.55 0)
			(layer "B.Fab")
			(hide yes)
			(effects
				(font
					(size 1 1)
					(thickness 0.15)
				)
				(justify mirror)
			)
		)
		(sheetname "/Supply/")
		(sheetfile "supply.kicad_sch")
		(attr smd)
		(fp_rect
			(start -0.925 0.47)
			(end 0.925 -0.47)
			(stroke
				(width 0.05)
				(type default)
			)
			(fill no)
			(layer "B.CrtYd")
		)
		(fp_rect
			(start -0.5 0.25)
			(end 0.5 -0.25)
			(stroke
				(width 0.15)
				(type solid)
			)
			(fill no)
			(layer "B.Fab")
		)
		(fp_text user "License: Apache-2.0"
			(at -0.95 -5.169 0)
			(layer "B.Fab")
			(effects
				(font
					(size 0.7 0.7)
					(thickness 0.15)
				)
				(justify left bottom mirror)
			)
		)
		(fp_text user "${REFERENCE}"
			(at -0.95 -3.168 0)
			(layer "B.Fab")
			(effects
				(font
					(size 0.7 0.7)
					(thickness 0.15)
				)
				(justify left bottom mirror)
			)
		)
		(fp_text user "Author: Antmicro"
			(at -0.95 -4.169 0)
			(layer "B.Fab")
			(effects
				(font
					(size 0.7 0.7)
					(thickness 0.15)
				)
				(justify left bottom mirror)
			)
		)
		(pad "1" smd roundrect
			(at -0.48 0 180)
			(size 0.59 0.64)
			(layers "B.Cu" "B.Mask" "B.Paste")
			(roundrect_rratio 0.25)
			(net 296 "Net-(R10-Pad2)")
			(pintype "passive")
		)
		(pad "2" smd roundrect
			(at 0.48 0 180)
			(size 0.59 0.64)
			(layers "B.Cu" "B.Mask" "B.Paste")
			(roundrect_rratio 0.25)
			(net 649 "VDD")
			(pintype "passive")
		)
	)
)
